(kicad_pcb
	(version 20241229)
	(generator "pcbnew")
	(generator_version "9.0")
	(general
		(thickness 1.63)
		(legacy_teardrops no)
	)
	(paper "A4")
	(title_block
		(title "CM4 Baseboard")
		(date "2026-01-05")
		(rev "1.1.1")
		(company "Antmicro Ltd")
		(comment 1 "www.antmicro.com")
		(comment 9 "footprints 381-383 of 506")
	)
	(layers
		(0 "F.Cu" signal)
		(4 "In1.Cu" power)
		(6 "In2.Cu" power)
		(8 "In3.Cu" signal)
		(10 "In4.Cu" signal)
		(2 "B.Cu" signal)
		(9 "F.Adhes" user "F.Adhesive")
		(11 "B.Adhes" user "B.Adhesive")
		(13 "F.Paste" user)
		(15 "B.Paste" user)
		(5 "F.SilkS" user "F.Silkscreen")
		(7 "B.SilkS" user "B.Silkscreen")
		(1 "F.Mask" user)
		(3 "B.Mask" user)
		(17 "Dwgs.User" user "User.Drawings")
		(19 "Cmts.User" user "User.Comments")
		(21 "Eco1.User" user "User.Eco1")
		(23 "Eco2.User" user "User.Eco2")
		(25 "Edge.Cuts" user)
		(27 "Margin" user)
		(31 "F.CrtYd" user "F.Courtyard")
		(29 "B.CrtYd" user "B.Courtyard")
		(35 "F.Fab" user)
		(33 "B.Fab" user)
	)
	(footprint "antmicro-footprints:R_Array_4x0402_Panasonic_EXB28V"
		(layer "B.Cu")
		(at 99.017962 169.9915 90)
		(property "Reference" "R706"
			(at 3.795 1.19 90)
			(layer "B.SilkS")
			(effects
				(font
					(size 0.7 0.7)
					(thickness 0.15)
				)
				(justify right bottom mirror)
			)
		)
		(property "Value" "R_4x100R_0402_array"
			(at -1.5 -2 90)
			(layer "B.Fab")
			(effects
				(font
					(size 0.7 0.7)
					(thickness 0.15)
				)
				(justify right bottom mirror)
			)
		)
		(property "Datasheet" "http://industrial.panasonic.com/cdbs/www-data/pdf/AOC0000/AOC0000C14.pdf"
			(at 0 0 90)
			(layer "B.Fab")
			(hide yes)
			(effects
				(font
					(size 1.27 1.27)
					(thickness 0.15)
				)
			)
		)
		(property "MPN" "EXB-28V101JX"
			(at 0 0 90)
			(unlocked yes)
			(layer "B.Fab")
			(hide yes)
			(effects
				(font
					(size 1 1)
					(thickness 0.15)
				)
				(justify mirror)
			)
		)
		(property "Manufacturer" "Panasonic"
			(at 0 0 90)
			(unlocked yes)
			(layer "B.Fab")
			(hide yes)
			(effects
				(font
					(size 1 1)
					(thickness 0.15)
				)
				(justify mirror)
			)
		)
		(property "Author" "Antmicro"
			(at 0 0 90)
			(unlocked yes)
			(layer "B.Fab")
			(hide yes)
			(effects
				(font
					(size 1 1)
					(thickness 0.15)
				)
				(justify mirror)
			)
		)
		(property "License" "Apache-2.0"
			(at 0 0 90)
			(unlocked yes)
			(layer "B.Fab")
			(hide yes)
			(effects
				(font
					(size 1 1)
					(thickness 0.15)
				)
				(justify mirror)
			)
		)
		(property "Val" "R_4x100R_0402"
			(at 0 0 90)
			(unlocked yes)
			(layer "B.Fab")
			(hide yes)
			(effects
				(font
					(size 1 1)
					(thickness 0.15)
				)
				(justify mirror)
			)
		)
		(sheetname "/Display/")
		(sheetfile "display.kicad_sch")
		(attr smd)
		(fp_line
			(start 1.25 -0.499)
			(end 1.25 0.499)
			(stroke
				(width 0.15)
				(type solid)
			)
			(layer "B.SilkS")
		)
		(fp_line
			(start -1.25 0.5)
			(end -1.25 -0.498)
			(stroke
				(width 0.15)
				(type solid)
			)
			(layer "B.SilkS")
		)
		(fp_rect
			(start -1.25 0.8)
			(end 1.25 -0.8)
			(stroke
				(width 0.05)
				(type solid)
			)
			(fill no)
			(layer "B.CrtYd")
		)
		(fp_line
			(start 0.998 -0.498)
			(end -1 -0.498)
			(stroke
				(width 0.15)
				(type solid)
			)
			(layer "B.Fab")
		)
		(fp_line
			(start -1 -0.498)
			(end -1 0.5)
			(stroke
				(width 0.15)
				(type solid)
			)
			(layer "B.Fab")
		)
		(fp_line
			(start 0.998 0.5)
			(end 0.998 -0.498)
			(stroke
				(width 0.15)
				(type solid)
			)
			(layer "B.Fab")
		)
		(fp_line
			(start -1 0.5)
			(end 0.998 0.5)
			(stroke
				(width 0.15)
				(type solid)
			)
			(layer "B.Fab")
		)
		(fp_text user "${REFERENCE}"
			(at -1.5 -3.25 270)
			(layer "B.Fab")
			(effects
				(font
					(size 0.7 0.7)
					(thickness 0.15)
				)
				(justify left bottom mirror)
			)
		)
		(fp_text user "Author: Antmicro"
			(at -1.5 -4.5 270)
			(layer "B.Fab")
			(effects
				(font
					(size 0.7 0.7)
					(thickness 0.15)
				)
				(justify left bottom mirror)
			)
		)
		(fp_text user "License: Apache-2.0"
			(at -1.5 -5.75 270)
			(layer "B.Fab")
			(effects
				(font
					(size 0.7 0.7)
					(thickness 0.15)
				)
				(justify left bottom mirror)
			)
		)
		(pad "1" smd roundrect
			(at -0.8875 -0.45 90)
			(size 0.525 0.5)
			(layers "B.Cu" "B.Mask" "B.Paste")
			(roundrect_rratio 0.25)
			(net 305 "Net-(R706-R1.1)")
			(pinfunction "R1.1")
			(pintype "passive")
		)
		(pad "2" smd roundrect
			(at -0.25 -0.45 90)
			(size 0.25 0.5)
			(layers "B.Cu" "B.Mask" "B.Paste")
			(roundrect_rratio 0.25)
			(net 306 "Net-(R706-R2.1)")
			(pinfunction "R2.1")
			(pintype "passive")
		)
		(pad "3" smd roundrect
			(at 0.25 -0.45 90)
			(size 0.25 0.5)
			(layers "B.Cu" "B.Mask" "B.Paste")
			(roundrect_rratio 0.25)
			(net 307 "Net-(R706-R3.1)")
			(pinfunction "R3.1")
			(pintype "passive")
		)
		(pad "4" smd roundrect
			(at 0.8875 -0.45 90)
			(size 0.525 0.5)
			(layers "B.Cu" "B.Mask" "B.Paste")
			(roundrect_rratio 0.25)
			(net 308 "Net-(R706-R4.1)")
			(pinfunction "R4.1")
			(pintype "passive")
		)
		(pad "5" smd roundrect
			(at 0.8875 0.45 90)
			(size 0.525 0.5)
			(layers "B.Cu" "B.Mask" "B.Paste")
			(roundrect_rratio 0.25)
			(net 125 "/Compute module/DSICtrl.GPIO")
			(pinfunction "R4.2")
			(pintype "passive")
		)
		(pad "6" smd roundrect
			(at 0.25 0.45 90)
			(size 0.25 0.5)
			(layers "B.Cu" "B.Mask" "B.Paste")
			(roundrect_rratio 0.25)
			(net 124 "/Compute module/DSICtrl.DIM")
			(pinfunction "R3.2")
			(pintype "passive")
		)
		(pad "7" smd roundrect
			(at -0.25 0.45 90)
			(size 0.25 0.5)
			(layers "B.Cu" "B.Mask" "B.Paste")
			(roundrect_rratio 0.25)
			(net 123 "/Compute module/DSICtrl.~{RST}")
			(pinfunction "R2.2")
			(pintype "passive")
		)
		(pad "8" smd roundrect
			(at -0.8875 0.45 90)
			(size 0.525 0.5)
			(layers "B.Cu" "B.Mask" "B.Paste")
			(roundrect_rratio 0.25)
			(net 122 "/Compute module/DSICtrl.EN")
			(pinfunction "R1.2")
			(pintype "passive")
		)
	)
	(footprint "antmicro-footprints:Nexperia_DFN-10_2.5x1mm_P0.5mm"
		(layer "B.Cu")
		(at 89.505962 169.1785 90)
		(property "Reference" "D703"
			(at -1.198 -1.908 90)
			(layer "B.SilkS")
			(effects
				(font
					(size 0.7 0.7)
					(thickness 0.15)
				)
				(justify right bottom mirror)
			)
		)
		(property "Value" "PUSB3F96X_PASS"
			(at -0.016 -1.705 90)
			(layer "B.Fab")
			(effects
				(font
					(size 0.7 0.7)
					(thickness 0.15)
				)
				(justify right bottom mirror)
			)
		)
		(property "Datasheet" "https://mouser.com/datasheet/2/916/PUSB3F96-1600324.pdf"
			(at 0 0 90)
			(layer "B.Fab")
			(hide yes)
			(effects
				(font
					(size 1.27 1.27)
					(thickness 0.15)
				)
			)
		)
		(property "Manufacturer" "Nexperia"
			(at 0 0 90)
			(unlocked yes)
			(layer "B.Fab")
			(hide yes)
			(effects
				(font
					(size 1 1)
					(thickness 0.15)
				)
				(justify mirror)
			)
		)
		(property "MPN" "PUSB3F96X"
			(at 0 0 90)
			(unlocked yes)
			(layer "B.Fab")
			(hide yes)
			(effects
				(font
					(size 1 1)
					(thickness 0.15)
				)
				(justify mirror)
			)
		)
		(property "Author" "Antmicro"
			(at 0 0 90)
			(unlocked yes)
			(layer "B.Fab")
			(hide yes)
			(effects
				(font
					(size 1 1)
					(thickness 0.15)
				)
				(justify mirror)
			)
		)
		(property "License" "Apache-2.0"
			(at 0 0 90)
			(unlocked yes)
			(layer "B.Fab")
			(hide yes)
			(effects
				(font
					(size 1 1)
					(thickness 0.15)
				)
				(justify mirror)
			)
		)
		(sheetname "/Display/")
		(sheetfile "display.kicad_sch")
		(attr smd)
		(fp_line
			(start 1.375 -0.4)
			(end 1.375 0.4)
			(stroke
				(width 0.15)
				(type solid)
			)
			(layer "B.SilkS")
		)
		(fp_line
			(start -1.375 0.4)
			(end -1.375 -0.4)
			(stroke
				(width 0.15)
				(type solid)
			)
			(layer "B.SilkS")
		)
		(fp_circle
			(center -1.4 -0.7)
			(end -1.349 -0.7)
			(stroke
				(width 0.15)
				(type solid)
			)
			(fill yes)
			(layer "B.SilkS")
		)
		(fp_rect
			(start -1.4 0.725)
			(end 1.4 -0.725)
			(stroke
				(width 0.05)
				(type solid)
			)
			(fill no)
			(layer "B.CrtYd")
		)
		(fp_line
			(start 1.25 -0.5)
			(end 1.25 0.5)
			(stroke
				(width 0.15)
				(type solid)
			)
			(layer "B.Fab")
		)
		(fp_line
			(start -0.9 -0.5)
			(end 1.25 -0.5)
			(stroke
				(width 0.15)
				(type solid)
			)
			(layer "B.Fab")
		)
		(fp_line
			(start -1.25 -0.15)
			(end -0.9 -0.5)
			(stroke
				(width 0.15)
				(type solid)
			)
			(layer "B.Fab")
		)
		(fp_line
			(start 1.25 0.5)
			(end -1.25 0.5)
			(stroke
				(width 0.15)
				(type solid)
			)
			(layer "B.Fab")
		)
		(fp_line
			(start -1.25 0.5)
			(end -1.25 -0.15)
			(stroke
				(width 0.15)
				(type solid)
			)
			(layer "B.Fab")
		)
		(fp_text user "${REFERENCE}"
			(at -1.367 -3.704 270)
			(layer "B.Fab")
			(effects
				(font
					(size 0.7 0.7)
					(thickness 0.15)
				)
				(justify left bottom mirror)
			)
		)
		(fp_text user "License: Apache-2.0"
			(at -1.367 -6.105 270)
			(layer "B.Fab")
			(effects
				(font
					(size 0.7 0.7)
					(thickness 0.15)
				)
				(justify left bottom mirror)
			)
		)
		(fp_text user "Author: Antmicro"
			(at -1.367 -4.905 270)
			(layer "B.Fab")
			(effects
				(font
					(size 0.7 0.7)
					(thickness 0.15)
				)
				(justify left bottom mirror)
			)
		)
		(pad "1" smd rect
			(at -1 -0.3875 90)
			(size 0.2 0.475)
			(layers "B.Cu" "B.Mask" "B.Paste")
			(net 76 "/Compute module/DSI.CLK_N")
			(pinfunction "CH1")
			(pintype "passive")
			(solder_mask_margin 0.05)
		)
		(pad "2" smd rect
			(at -0.5 -0.3875 90)
			(size 0.2 0.475)
			(layers "B.Cu" "B.Mask" "B.Paste")
			(net 86 "/Compute module/DSI.CLK_P")
			(pinfunction "CH2")
			(pintype "passive")
			(solder_mask_margin 0.05)
		)
		(pad "3" smd rect
			(at 0 -0.3875 90)
			(size 0.2 0.475)
			(layers "B.Cu" "B.Mask" "B.Paste")
			(net 3 "GND")
			(pinfunction "GND")
			(pintype "passive")
			(solder_mask_margin 0.05)
		)
		(pad "4" smd rect
			(at 0.5 -0.3875 90)
			(size 0.2 0.475)
			(layers "B.Cu" "B.Mask" "B.Paste")
			(net 3 "GND")
			(pinfunction "CH3")
			(pintype "passive")
			(solder_mask_margin 0.05)
		)
		(pad "5" smd rect
			(at 1 -0.3875 90)
			(size 0.2 0.475)
			(layers "B.Cu" "B.Mask" "B.Paste")
			(net 3 "GND")
			(pinfunction "CH4")
			(pintype "passive")
			(solder_mask_margin 0.05)
		)
		(pad "6" smd rect
			(at 1 0.3875 90)
			(size 0.2 0.475)
			(layers "B.Cu" "B.Mask" "B.Paste")
			(net 3 "GND")
			(pinfunction "CH4")
			(pintype "passive")
			(solder_mask_margin 0.05)
		)
		(pad "7" smd rect
			(at 0.5 0.3875 90)
			(size 0.2 0.475)
			(layers "B.Cu" "B.Mask" "B.Paste")
			(net 3 "GND")
			(pinfunction "CH3")
			(pintype "passive")
			(solder_mask_margin 0.05)
		)
		(pad "8" smd rect
			(at 0 0.3875 90)
			(size 0.2 0.475)
			(layers "B.Cu" "B.Mask" "B.Paste")
			(net 3 "GND")
			(pinfunction "GND")
			(pintype "passive")
			(solder_mask_margin 0.05)
		)
		(pad "9" smd rect
			(at -0.501 0.3875 90)
			(size 0.2 0.475)
			(layers "B.Cu" "B.Mask" "B.Paste")
			(net 86 "/Compute module/DSI.CLK_P")
			(pinfunction "CH2")
			(pintype "passive")
			(solder_mask_margin 0.05)
		)
		(pad "10" smd rect
			(at -1 0.3875 90)
			(size 0.2 0.475)
			(layers "B.Cu" "B.Mask" "B.Paste")
			(net 76 "/Compute module/DSI.CLK_N")
			(pinfunction "CH1")
			(pintype "passive")
			(solder_mask_margin 0.05)
		)
	)
	(footprint "antmicro-footprints:R_0402_1005Metric"
		(layer "B.Cu")
		(at 84.667962 123.7165 180)
		(descr "Resistor SMD 0402")
		(tags "resistor SMD 0402")
		(property "Reference" "R912"
			(at 1 -0.32 0)
			(layer "B.SilkS")
			(effects
				(font
					(size 0.7 0.7)
					(thickness 0.15)
				)
				(justify left bottom mirror)
			)
		)
		(property "Value" "R_6k8_0402"
			(at -1.011843 -1.772047 0)
			(layer "B.Fab")
			(effects
				(font
					(size 0.7 0.7)
					(thickness 0.15)
				)
				(justify left bottom mirror)
			)
		)
		(property "Datasheet" "https://www.bourns.com/docs/product-datasheets/cr.pdf"
			(at 0 0 180)
			(layer "B.Fab")
			(hide yes)
			(effects
				(font
					(size 1.27 1.27)
					(thickness 0.15)
				)
			)
		)
		(property "MPN" "CR0402-FX-6801GLF"
			(at 0 0 180)
			(unlocked yes)
			(layer "B.Fab")
			(hide yes)
			(effects
				(font
					(size 1 1)
					(thickness 0.15)
				)
				(justify mirror)
			)
		)
		(property "Manufacturer" "Bourns"
			(at 0 0 180)
			(unlocked yes)
			(layer "B.Fab")
			(hide yes)
			(effects
				(font
					(size 1 1)
					(thickness 0.15)
				)
				(justify mirror)
			)
		)
		(property "License" "Apache-2.0"
			(at 0 0 180)
			(unlocked yes)
			(layer "B.Fab")
			(hide yes)
			(effects
				(font
					(size 1 1)
					(thickness 0.15)
				)
				(justify mirror)
			)
		)
		(property "Author" "Antmicro"
			(at 0 0 180)
			(unlocked yes)
			(layer "B.Fab")
			(hide yes)
			(effects
				(font
					(size 1 1)
					(thickness 0.15)
				)
				(justify mirror)
			)
		)
		(property "Val" "6k8"
			(at 0 0 180)
			(unlocked yes)
			(layer "B.Fab")
			(hide yes)
			(effects
				(font
					(size 1 1)
					(thickness 0.15)
				)
				(justify mirror)
			)
		)
		(property "Tolerance" "1%"
			(at 0 0 180)
			(unlocked yes)
			(layer "B.Fab")
			(hide yes)
			(effects
				(font
					(size 1 1)
					(thickness 0.15)
				)
				(justify mirror)
			)
		)
		(sheetname "/USB/")
		(sheetfile "usb.kicad_sch")
		(attr smd)
		(fp_rect
			(start -0.925 0.47)
			(end 0.925 -0.47)
			(stroke
				(width 0.05)
				(type default)
			)
			(fill no)
			(layer "B.CrtYd")
		)
		(fp_rect
			(start -0.5 0.25)
			(end 0.5 -0.25)
			(stroke
				(width 0.15)
				(type solid)
			)
			(fill no)
			(layer "B.Fab")
		)
		(fp_text user "Author: Antmicro"
			(at -0.95 -4.169 0)
			(layer "B.Fab")
			(effects
				(font
					(size 0.7 0.7)
					(thickness 0.15)
				)
				(justify left bottom mirror)
			)
		)
		(fp_text user "License: Apache-2.0"
			(at -0.95 -5.169 0)
			(layer "B.Fab")
			(effects
				(font
					(size 0.7 0.7)
					(thickness 0.15)
				)
				(justify left bottom mirror)
			)
		)
		(fp_text user "${REFERENCE}"
			(at -0.95 -3.168 0)
			(layer "B.Fab")
			(effects
				(font
					(size 0.7 0.7)
					(thickness 0.15)
				)
				(justify left bottom mirror)
			)
		)
		(pad "1" smd roundrect
			(at -0.48 0 180)
			(size 0.59 0.64)
			(layers "B.Cu" "B.Mask" "B.Paste")
			(roundrect_rratio 0.25)
			(net 344 "/USB/FB_FTDI")
			(pintype "passive")
		)
		(pad "2" smd roundrect
			(at 0.48 0 180)
			(size 0.59 0.64)
			(layers "B.Cu" "B.Mask" "B.Paste")
			(roundrect_rratio 0.25)
			(net 113 "/USB/OUT_FTDI")
			(pintype "passive")
		)
	)
)
